FILE_TYPE=LIBRARY_PARTS;
primitive 'NCP3284AMNTXG';
  pin
    'NC2':
      PIN_NUMBER='(34)';
      OUTPUT_TYPE='(TS,TS)';
      INPUT_LOAD='(-0.01,0.01)';
      OUTPUT_LOAD='(1.0,-1.0)';
    'MODE||FSET':
      PIN_NUMBER='(36)';
      INPUT_LOAD='(-0.01,0.01)';
    'VIN':
      PIN_NUMBER='(3)';
      PINUSE='POWER';
      NO_LOAD_CHECK='Both';
      NO_IO_CHECK='Both';
      NO_ASSERT_CHECK='TRUE';
      NO_DIR_CHECK='TRUE';
      ALLOW_CONNECT='TRUE';
    'FB':
      PIN_NUMBER='(30)';
      INPUT_LOAD='(-0.01,0.01)';
    'BOOT':
      PIN_NUMBER='(26)';
      BIDIRECTIONAL='TRUE';
      INPUT_LOAD='(-0.01,0.01)';
      OUTPUT_LOAD='(1.0,-1.0)';
    'ILIM':
      PIN_NUMBER='(1)';
      OUTPUT_LOAD='(1.0,-1.0)';
    'PHASE':
      PIN_NUMBER='(25)';
      INPUT_LOAD='(-0.01,0.01)';
    'VCC':
      PIN_NUMBER='(4)';
      PINUSE='POWER';
      NO_LOAD_CHECK='Both';
      NO_IO_CHECK='Both';
      NO_ASSERT_CHECK='TRUE';
      NO_DIR_CHECK='TRUE';
      ALLOW_CONNECT='TRUE';
    'VSNS-':
      PIN_NUMBER='(31)';
      INPUT_LOAD='(-0.01,0.01)';
    'HICCUP#':
      PIN_NUMBER='(35)';
      INPUT_LOAD='(-0.01,0.01)';
    'PGND':
      PIN_NUMBER='(7_10-19)';
      PINUSE='POWER';
      NO_LOAD_CHECK='Both';
      NO_IO_CHECK='Both';
      NO_ASSERT_CHECK='TRUE';
      NO_DIR_CHECK='TRUE';
      ALLOW_CONNECT='TRUE';
    'NC1':
      PIN_NUMBER='(33)';
      OUTPUT_TYPE='(TS,TS)';
      INPUT_LOAD='(-0.01,0.01)';
      OUTPUT_LOAD='(1.0,-1.0)';
    'SW':
      PIN_NUMBER='(11_18)';
      BIDIRECTIONAL='TRUE';
      INPUT_LOAD='(-0.01,0.01)';
      OUTPUT_LOAD='(1.0,-1.0)';
    'PVIN':
      PIN_NUMBER='(20_24)';
      PINUSE='POWER';
      NO_LOAD_CHECK='Both';
      NO_IO_CHECK='Both';
      NO_ASSERT_CHECK='TRUE';
      NO_DIR_CHECK='TRUE';
      ALLOW_CONNECT='TRUE';
    'PGOOD':
      PIN_NUMBER='(2)';
      OUTPUT_LOAD='(1.0,-1.0)';
    'VOS':
      PIN_NUMBER='(28)';
      INPUT_LOAD='(-0.01,0.01)';
    'AGND':
      PIN_NUMBER='(32)';
      PINUSE='POWER';
      NO_LOAD_CHECK='Both';
      NO_IO_CHECK='Both';
      NO_ASSERT_CHECK='TRUE';
      NO_DIR_CHECK='TRUE';
      ALLOW_CONNECT='TRUE';
    'EN':
      PIN_NUMBER='(27)';
      INPUT_LOAD='(-0.01,0.01)';
    'VDRV':
      PIN_NUMBER='(5)';
      PINUSE='POWER';
      NO_LOAD_CHECK='Both';
      NO_IO_CHECK='Both';
      NO_ASSERT_CHECK='TRUE';
      NO_DIR_CHECK='TRUE';
      ALLOW_CONNECT='TRUE';
    'GL1':
      PIN_NUMBER='(6)';
      OUTPUT_LOAD='(1.0,-1.0)';
    'SS':
      PIN_NUMBER='(29)';
      INPUT_LOAD='(-0.01,0.01)';
    'GL2':
      PIN_NUMBER='(37)';
      OUTPUT_LOAD='(1.0,-1.0)';
  end_pin;
  body
    PART_NAME='NCP3284AMNTXG';
    BODY_NAME='NCP3284AMNTXG';
    PHYS_DES_PREFIX='U';
    CLASS='IC';
  end_body;
end_primitive;

END.
